(kicad_pcb
	(version 20260206)
	(generator "pcbnew")
	(generator_version "10.0")
	(general
		(thickness 1.6)
		(legacy_teardrops no)
	)
	(paper "A4")
	(title_block
		(title "v2-pdb — ms_pdb_v2.brd")
		(comment 1 "Open CloudServer (Microsoft) / footprint 117 of 348 (J25), pads 1-78 of 166")
	)
	(layers
		(0 "F.Cu" signal "TOP")
		(4 "In1.Cu" signal "GND")
		(6 "In2.Cu" signal "IN1")
		(8 "In3.Cu" signal "VCC")
		(10 "In4.Cu" signal "VCC1")
		(12 "In5.Cu" signal "IN2")
		(14 "In6.Cu" signal "GND1")
		(2 "B.Cu" signal "BOTTOM")
		(9 "F.Adhes" user "F.Adhesive")
		(11 "B.Adhes" user "B.Adhesive")
		(13 "F.Paste" user "Package Geometry/Pastemask Top")
		(15 "B.Paste" user "Package Geometry/Pastemask Bottom")
		(5 "F.SilkS" user "Ref Des/Silkscreen Top")
		(7 "B.SilkS" user "Ref Des/Silkscreen Bottom")
		(1 "F.Mask" user "Board Geometry/Soldermask Top")
		(3 "B.Mask" user "Board Geometry/Soldermask Bottom")
		(17 "Dwgs.User" user "User.Drawings")
		(19 "Cmts.User" user "User.Comments")
		(21 "Eco1.User" user "User.Eco1")
		(23 "Eco2.User" user "User.Eco2")
		(25 "Edge.Cuts" user "Board Geometry/Outline")
		(27 "Margin" user)
		(31 "F.CrtYd" user "Package Geometry/Place Bound Top")
		(29 "B.CrtYd" user "Package Geometry/Place Bound Bottom")
		(35 "F.Fab" user "Ref Des/Assembly Top")
		(33 "B.Fab" user "Ref Des/Assembly Bottom")
	)
	(footprint ""
		(layer "F.Cu")
		(at 6.449822 -352.669856)
		(property "Reference" "J25"
			(at 6.653784 1.81356 90)
			(unlocked yes)
			(layer "F.SilkS")
			(effects
				(font
					(size 0.7874 0.5842)
					(thickness 0.1524)
				)
				(justify left)
			)
		)
		(property "Value" ""
			(at 0 0 0)
			(layer "F.Fab")
			(effects
				(font
					(size 1.27 1.27)
				)
			)
		)
		(duplicate_pad_numbers_are_jumpers no)
		(pad "" np_thru_hole circle
			(at -1.249934 11.649964 270)
			(size 2.413 2.413)
			(drill 2.413)
			(layers "*.Cu" "*.Mask")
			(clearance 0.381)
			(thermal_gap 0.381)
		)
		(pad "" np_thru_hole circle
			(at -1.249934 84.799932 270)
			(size 2.413 2.413)
			(drill 2.413)
			(layers "*.Cu" "*.Mask")
			(clearance 0.381)
			(thermal_gap 0.381)
		)
		(pad "A1" thru_hole rect
			(at 0 0 270)
			(size 1.016 1.016)
			(drill 0.7112)
			(layers "*.Cu" "*.Mask")
			(remove_unused_layers no)
			(net "MATE_A1")
			(clearance 0.1016)
			(thermal_gap 0.1016)
			(padstack
				(mode front_inner_back)
				(layer "Inner"
					(shape circle)
					(size 1.016 1.016)
					(clearance 0.1016)
				)
				(layer "B.Cu"
					(shape rect)
					(size 1.016 1.016)
					(clearance 0.1016)
				)
			)
		)
		(pad "A2" thru_hole circle
			(at 1.999996 0.999998 270)
			(size 1.016 1.016)
			(drill 0.7112)
			(layers "*.Cu" "*.Mask")
			(remove_unused_layers no)
			(net "GND")
			(clearance 0.1016)
			(thermal_gap 0.1016)
		)
		(pad "A3" thru_hole circle
			(at 0 1.999996 270)
			(size 1.016 1.016)
			(drill 0.7112)
			(layers "*.Cu" "*.Mask")
			(remove_unused_layers no)
			(net "LAN2_P3_P")
			(clearance 0.1016)
			(thermal_gap 0.1016)
		)
		(pad "A4" thru_hole circle
			(at 1.999996 2.999994 270)
			(size 1.016 1.016)
			(drill 0.7112)
			(layers "*.Cu" "*.Mask")
			(remove_unused_layers no)
			(net "LAN2_P3_N")
			(clearance 0.1016)
			(thermal_gap 0.1016)
		)
		(pad "A5" thru_hole circle
			(at 0 3.999992 270)
			(size 1.016 1.016)
			(drill 0.7112)
			(layers "*.Cu" "*.Mask")
			(remove_unused_layers no)
			(net "GND")
			(clearance 0.1016)
			(thermal_gap 0.1016)
		)
		(pad "A6" thru_hole circle
			(at 1.999996 4.99999 270)
			(size 1.016 1.016)
			(drill 0.7112)
			(layers "*.Cu" "*.Mask")
			(remove_unused_layers no)
			(net "LAN2_P4_P")
			(clearance 0.1016)
			(thermal_gap 0.1016)
		)
		(pad "A7" thru_hole circle
			(at 0 5.999988 270)
			(size 1.016 1.016)
			(drill 0.7112)
			(layers "*.Cu" "*.Mask")
			(remove_unused_layers no)
			(net "LAN2_P4_N")
			(clearance 0.1016)
			(thermal_gap 0.1016)
		)
		(pad "A8" thru_hole circle
			(at 1.999996 6.999986 270)
			(size 1.016 1.016)
			(drill 0.7112)
			(layers "*.Cu" "*.Mask")
			(remove_unused_layers no)
			(net "GND")
			(clearance 0.1016)
			(thermal_gap 0.1016)
		)
		(pad "A9" thru_hole circle
			(at 0 7.999984 270)
			(size 1.016 1.016)
			(drill 0.7112)
			(layers "*.Cu" "*.Mask")
			(remove_unused_layers no)
			(net "POWER_SW3_PWR_CTR_12V")
			(clearance 0.1016)
			(thermal_gap 0.1016)
		)
		(pad "A10" thru_hole circle
			(at 1.999996 8.999982 270)
			(size 1.016 1.016)
			(drill 0.7112)
			(layers "*.Cu" "*.Mask")
			(remove_unused_layers no)
			(net "POWER_SW2_PWR_CTR_12V")
			(clearance 0.1016)
			(thermal_gap 0.1016)
		)
		(pad "A11" thru_hole circle
			(at 0 9.99998 270)
			(size 1.016 1.016)
			(drill 0.7112)
			(layers "*.Cu" "*.Mask")
			(remove_unused_layers no)
			(net "POWER_SW1_PWR_CTR_12V")
			(clearance 0.1016)
			(thermal_gap 0.1016)
		)
		(pad "A12" thru_hole circle
			(at 1.999996 12.999974 270)
			(size 1.016 1.016)
			(drill 0.7112)
			(layers "*.Cu" "*.Mask")
			(remove_unused_layers no)
			(net "GND36")
			(clearance 0.1016)
			(thermal_gap 0.1016)
		)
		(pad "A13" thru_hole circle
			(at 0 13.999972 270)
			(size 1.016 1.016)
			(drill 0.7112)
			(layers "*.Cu" "*.Mask")
			(remove_unused_layers no)
			(net "Net_439")
			(clearance 0.1016)
			(thermal_gap 0.1016)
		)
		(pad "A14" thru_hole circle
			(at 1.999996 14.99997 270)
			(size 1.016 1.016)
			(drill 0.7112)
			(layers "*.Cu" "*.Mask")
			(remove_unused_layers no)
			(net "Net_438")
			(clearance 0.1016)
			(thermal_gap 0.1016)
		)
		(pad "A15" thru_hole circle
			(at 0 15.999968 270)
			(size 1.016 1.016)
			(drill 0.7112)
			(layers "*.Cu" "*.Mask")
			(remove_unused_layers no)
			(net "GND37")
			(clearance 0.1016)
			(thermal_gap 0.1016)
		)
		(pad "A16" thru_hole circle
			(at 1.999996 16.999966 270)
			(size 1.016 1.016)
			(drill 0.7112)
			(layers "*.Cu" "*.Mask")
			(remove_unused_layers no)
			(net "Net_443")
			(clearance 0.1016)
			(thermal_gap 0.1016)
		)
		(pad "A17" thru_hole circle
			(at 0 17.999964 270)
			(size 1.016 1.016)
			(drill 0.7112)
			(layers "*.Cu" "*.Mask")
			(remove_unused_layers no)
			(net "GND")
			(clearance 0.1016)
			(thermal_gap 0.1016)
		)
		(pad "A18" thru_hole circle
			(at 1.999996 18.999962 270)
			(size 1.016 1.016)
			(drill 0.7112)
			(layers "*.Cu" "*.Mask")
			(remove_unused_layers no)
			(net "GND38")
			(clearance 0.1016)
			(thermal_gap 0.1016)
		)
		(pad "A19" thru_hole circle
			(at 0 19.99996 270)
			(size 1.016 1.016)
			(drill 0.7112)
			(layers "*.Cu" "*.Mask")
			(remove_unused_layers no)
			(net "Net_6")
			(clearance 0.1016)
			(thermal_gap 0.1016)
		)
		(pad "A20" thru_hole circle
			(at 1.999996 20.999958 270)
			(size 1.016 1.016)
			(drill 0.7112)
			(layers "*.Cu" "*.Mask")
			(remove_unused_layers no)
			(net "GND39")
			(clearance 0.1016)
			(thermal_gap 0.1016)
		)
		(pad "A21" thru_hole circle
			(at 0 21.999956 270)
			(size 1.016 1.016)
			(drill 0.7112)
			(layers "*.Cu" "*.Mask")
			(remove_unused_layers no)
			(net "Net_4")
			(clearance 0.1016)
			(thermal_gap 0.1016)
		)
		(pad "A22" thru_hole circle
			(at 1.999996 22.999954 270)
			(size 1.016 1.016)
			(drill 0.7112)
			(layers "*.Cu" "*.Mask")
			(remove_unused_layers no)
			(net "Net_5")
			(clearance 0.1016)
			(thermal_gap 0.1016)
		)
		(pad "A23" thru_hole circle
			(at 0 23.999952 270)
			(size 1.016 1.016)
			(drill 0.7112)
			(layers "*.Cu" "*.Mask")
			(remove_unused_layers no)
			(net "GND40")
			(clearance 0.1016)
			(thermal_gap 0.1016)
		)
		(pad "A24" thru_hole circle
			(at 1.999996 24.99995 270)
			(size 1.016 1.016)
			(drill 0.7112)
			(layers "*.Cu" "*.Mask")
			(remove_unused_layers no)
			(net "GND41")
			(clearance 0.1016)
			(thermal_gap 0.1016)
		)
		(pad "A25" thru_hole circle
			(at 0 25.999948 270)
			(size 1.016 1.016)
			(drill 0.7112)
			(layers "*.Cu" "*.Mask")
			(remove_unused_layers no)
			(net "GND")
			(clearance 0.1016)
			(thermal_gap 0.1016)
		)
		(pad "A26" thru_hole circle
			(at 1.999996 26.999946 270)
			(size 1.016 1.016)
			(drill 0.7112)
			(layers "*.Cu" "*.Mask")
			(remove_unused_layers no)
			(net "FAN4_TACH")
			(clearance 0.1016)
			(thermal_gap 0.1016)
		)
		(pad "A27" thru_hole circle
			(at 0 27.999944 270)
			(size 1.016 1.016)
			(drill 0.7112)
			(layers "*.Cu" "*.Mask")
			(remove_unused_layers no)
			(net "FAN5_TACH")
			(clearance 0.1016)
			(thermal_gap 0.1016)
		)
		(pad "A28" thru_hole circle
			(at 1.999996 28.999942 270)
			(size 1.016 1.016)
			(drill 0.7112)
			(layers "*.Cu" "*.Mask")
			(remove_unused_layers no)
			(net "FAN6_TACH")
			(clearance 0.1016)
			(thermal_gap 0.1016)
		)
		(pad "A29" thru_hole circle
			(at 0 29.99994 270)
			(size 1.016 1.016)
			(drill 0.7112)
			(layers "*.Cu" "*.Mask")
			(remove_unused_layers no)
			(net "GND")
			(clearance 0.1016)
			(thermal_gap 0.1016)
		)
		(pad "A30" thru_hole circle
			(at 1.999996 30.999938 270)
			(size 1.016 1.016)
			(drill 0.7112)
			(layers "*.Cu" "*.Mask")
			(remove_unused_layers no)
			(net "FAN_PWM")
			(clearance 0.1016)
			(thermal_gap 0.1016)
		)
		(pad "A31" thru_hole circle
			(at 0 31.999936 270)
			(size 1.016 1.016)
			(drill 0.7112)
			(layers "*.Cu" "*.Mask")
			(remove_unused_layers no)
			(net "GND")
			(clearance 0.1016)
			(thermal_gap 0.1016)
		)
		(pad "A32" thru_hole circle
			(at 1.999996 32.999934 270)
			(size 1.016 1.016)
			(drill 0.7112)
			(layers "*.Cu" "*.Mask")
			(remove_unused_layers no)
			(net "I2C_PSU3_SCL")
			(clearance 0.1016)
			(thermal_gap 0.1016)
		)
		(pad "A33" thru_hole circle
			(at 0 33.999932 270)
			(size 1.016 1.016)
			(drill 0.7112)
			(layers "*.Cu" "*.Mask")
			(remove_unused_layers no)
			(net "I2C_PSU3_SDA")
			(clearance 0.1016)
			(thermal_gap 0.1016)
		)
		(pad "A34" thru_hole circle
			(at 1.999996 34.99993 270)
			(size 1.016 1.016)
			(drill 0.7112)
			(layers "*.Cu" "*.Mask")
			(remove_unused_layers no)
			(net "GND")
			(clearance 0.1016)
			(thermal_gap 0.1016)
		)
		(pad "A35" thru_hole circle
			(at 0 35.999928 270)
			(size 1.016 1.016)
			(drill 0.7112)
			(layers "*.Cu" "*.Mask")
			(remove_unused_layers no)
			(net "T11_BLAD1_EN")
			(clearance 0.1016)
			(thermal_gap 0.1016)
		)
		(pad "A36" thru_hole circle
			(at 1.999996 36.999926 270)
			(size 1.016 1.016)
			(drill 0.7112)
			(layers "*.Cu" "*.Mask")
			(remove_unused_layers no)
			(net "TP_T11_BLAD2_EN")
			(clearance 0.1016)
			(thermal_gap 0.1016)
		)
		(pad "A37" thru_hole circle
			(at 0 37.999924 270)
			(size 1.016 1.016)
			(drill 0.7112)
			(layers "*.Cu" "*.Mask")
			(remove_unused_layers no)
			(net "T11_BLAD3_EN")
			(clearance 0.1016)
			(thermal_gap 0.1016)
		)
		(pad "A38" thru_hole circle
			(at 1.999996 38.999922 270)
			(size 1.016 1.016)
			(drill 0.7112)
			(layers "*.Cu" "*.Mask")
			(remove_unused_layers no)
			(net "TP_T11_BLAD4_EN")
			(clearance 0.1016)
			(thermal_gap 0.1016)
		)
		(pad "A39" thru_hole circle
			(at 0 39.99992 270)
			(size 1.016 1.016)
			(drill 0.7112)
			(layers "*.Cu" "*.Mask")
			(remove_unused_layers no)
			(net "GND")
			(clearance 0.1016)
			(thermal_gap 0.1016)
		)
		(pad "A40" thru_hole circle
			(at 1.999996 40.999918 270)
			(size 1.016 1.016)
			(drill 0.7112)
			(layers "*.Cu" "*.Mask")
			(remove_unused_layers no)
			(net "T11_BLAD1_RXD")
			(clearance 0.1016)
			(thermal_gap 0.1016)
		)
		(pad "A41" thru_hole circle
			(at 0 41.999916 270)
			(size 1.016 1.016)
			(drill 0.7112)
			(layers "*.Cu" "*.Mask")
			(remove_unused_layers no)
			(net "T11_BLAD1_TXD")
			(clearance 0.1016)
			(thermal_gap 0.1016)
		)
		(pad "A42" thru_hole circle
			(at 1.999996 42.999914 270)
			(size 1.016 1.016)
			(drill 0.7112)
			(layers "*.Cu" "*.Mask")
			(remove_unused_layers no)
			(net "T11_BLAD2_RXD")
			(clearance 0.1016)
			(thermal_gap 0.1016)
		)
		(pad "A43" thru_hole circle
			(at 0 43.999912 270)
			(size 1.016 1.016)
			(drill 0.7112)
			(layers "*.Cu" "*.Mask")
			(remove_unused_layers no)
			(net "T11_BLAD2_TXD")
			(clearance 0.1016)
			(thermal_gap 0.1016)
		)
		(pad "A44" thru_hole circle
			(at 1.999996 44.99991 270)
			(size 1.016 1.016)
			(drill 0.7112)
			(layers "*.Cu" "*.Mask")
			(remove_unused_layers no)
			(net "GND")
			(clearance 0.1016)
			(thermal_gap 0.1016)
		)
		(pad "A45" thru_hole circle
			(at 0 45.999908 270)
			(size 1.016 1.016)
			(drill 0.7112)
			(layers "*.Cu" "*.Mask")
			(remove_unused_layers no)
			(net "T11_BLAD3_RXD")
			(clearance 0.1016)
			(thermal_gap 0.1016)
		)
		(pad "A46" thru_hole circle
			(at 1.999996 46.999906 270)
			(size 1.016 1.016)
			(drill 0.7112)
			(layers "*.Cu" "*.Mask")
			(remove_unused_layers no)
			(net "T11_BLAD3_TXD")
			(clearance 0.1016)
			(thermal_gap 0.1016)
		)
		(pad "A47" thru_hole circle
			(at 0 47.999904 270)
			(size 1.016 1.016)
			(drill 0.7112)
			(layers "*.Cu" "*.Mask")
			(remove_unused_layers no)
			(net "T11_BLAD4_RXD")
			(clearance 0.1016)
			(thermal_gap 0.1016)
		)
		(pad "A48" thru_hole circle
			(at 1.999996 48.999902 270)
			(size 1.016 1.016)
			(drill 0.7112)
			(layers "*.Cu" "*.Mask")
			(remove_unused_layers no)
			(net "T11_BLAD4_TXD")
			(clearance 0.1016)
			(thermal_gap 0.1016)
		)
		(pad "A49" thru_hole circle
			(at 0 49.9999 270)
			(size 1.016 1.016)
			(drill 0.7112)
			(layers "*.Cu" "*.Mask")
			(remove_unused_layers no)
			(net "GND")
			(clearance 0.1016)
			(thermal_gap 0.1016)
		)
		(pad "A50" thru_hole circle
			(at 1.999996 50.999898 270)
			(size 1.016 1.016)
			(drill 0.7112)
			(layers "*.Cu" "*.Mask")
			(remove_unused_layers no)
			(net "T9_BLAD1_EN")
			(clearance 0.1016)
			(thermal_gap 0.1016)
		)
		(pad "A51" thru_hole circle
			(at 0 51.999896 270)
			(size 1.016 1.016)
			(drill 0.7112)
			(layers "*.Cu" "*.Mask")
			(remove_unused_layers no)
			(net "TP_T9_BLAD2_EN")
			(clearance 0.1016)
			(thermal_gap 0.1016)
		)
		(pad "A52" thru_hole circle
			(at 1.999996 52.999894 270)
			(size 1.016 1.016)
			(drill 0.7112)
			(layers "*.Cu" "*.Mask")
			(remove_unused_layers no)
			(net "T9_BLAD3_EN")
			(clearance 0.1016)
			(thermal_gap 0.1016)
		)
		(pad "A53" thru_hole circle
			(at 0 53.999892 270)
			(size 1.016 1.016)
			(drill 0.7112)
			(layers "*.Cu" "*.Mask")
			(remove_unused_layers no)
			(net "TP_T9_BLAD4_EN")
			(clearance 0.1016)
			(thermal_gap 0.1016)
		)
		(pad "A54" thru_hole circle
			(at 1.999996 54.99989 270)
			(size 1.016 1.016)
			(drill 0.7112)
			(layers "*.Cu" "*.Mask")
			(remove_unused_layers no)
			(net "GND")
			(clearance 0.1016)
			(thermal_gap 0.1016)
		)
		(pad "A55" thru_hole circle
			(at 0 55.999888 270)
			(size 1.016 1.016)
			(drill 0.7112)
			(layers "*.Cu" "*.Mask")
			(remove_unused_layers no)
			(net "T9_BLAD1_RXD")
			(clearance 0.1016)
			(thermal_gap 0.1016)
		)
		(pad "A56" thru_hole circle
			(at 1.999996 56.999886 270)
			(size 1.016 1.016)
			(drill 0.7112)
			(layers "*.Cu" "*.Mask")
			(remove_unused_layers no)
			(net "T9_BLAD1_TXD")
			(clearance 0.1016)
			(thermal_gap 0.1016)
		)
		(pad "A57" thru_hole circle
			(at 0 57.999884 270)
			(size 1.016 1.016)
			(drill 0.7112)
			(layers "*.Cu" "*.Mask")
			(remove_unused_layers no)
			(net "T9_BLAD2_RXD")
			(clearance 0.1016)
			(thermal_gap 0.1016)
		)
		(pad "A58" thru_hole circle
			(at 1.999996 59.000136 270)
			(size 1.016 1.016)
			(drill 0.7112)
			(layers "*.Cu" "*.Mask")
			(remove_unused_layers no)
			(net "T9_BLAD2_TXD")
			(clearance 0.1016)
			(thermal_gap 0.1016)
		)
		(pad "A59" thru_hole circle
			(at 0 59.99988 270)
			(size 1.016 1.016)
			(drill 0.7112)
			(layers "*.Cu" "*.Mask")
			(remove_unused_layers no)
			(net "GND")
			(clearance 0.1016)
			(thermal_gap 0.1016)
		)
		(pad "A60" thru_hole circle
			(at 1.999996 61.000132 270)
			(size 1.016 1.016)
			(drill 0.7112)
			(layers "*.Cu" "*.Mask")
			(remove_unused_layers no)
			(net "T9_BLAD3_RXD")
			(clearance 0.1016)
			(thermal_gap 0.1016)
		)
		(pad "A61" thru_hole circle
			(at 0 61.999876 270)
			(size 1.016 1.016)
			(drill 0.7112)
			(layers "*.Cu" "*.Mask")
			(remove_unused_layers no)
			(net "T9_BLAD3_TXD")
			(clearance 0.1016)
			(thermal_gap 0.1016)
		)
		(pad "A62" thru_hole circle
			(at 1.999996 63.000128 270)
			(size 1.016 1.016)
			(drill 0.7112)
			(layers "*.Cu" "*.Mask")
			(remove_unused_layers no)
			(net "T9_BLAD4_RXD")
			(clearance 0.1016)
			(thermal_gap 0.1016)
		)
		(pad "A63" thru_hole circle
			(at 0 63.999872 270)
			(size 1.016 1.016)
			(drill 0.7112)
			(layers "*.Cu" "*.Mask")
			(remove_unused_layers no)
			(net "T9_BLAD4_TXD")
			(clearance 0.1016)
			(thermal_gap 0.1016)
		)
		(pad "A64" thru_hole circle
			(at 1.999996 65.000124 270)
			(size 1.016 1.016)
			(drill 0.7112)
			(layers "*.Cu" "*.Mask")
			(remove_unused_layers no)
			(net "GND")
			(clearance 0.1016)
			(thermal_gap 0.1016)
		)
		(pad "A65" thru_hole circle
			(at 0 65.999868 270)
			(size 1.016 1.016)
			(drill 0.7112)
			(layers "*.Cu" "*.Mask")
			(remove_unused_layers no)
			(net "T7_BLAD1_EN")
			(clearance 0.1016)
			(thermal_gap 0.1016)
		)
		(pad "A66" thru_hole circle
			(at 1.999996 67.00012 270)
			(size 1.016 1.016)
			(drill 0.7112)
			(layers "*.Cu" "*.Mask")
			(remove_unused_layers no)
			(net "TP_T7_BLAD2_EN")
			(clearance 0.1016)
			(thermal_gap 0.1016)
		)
		(pad "A67" thru_hole circle
			(at 0 67.999864 270)
			(size 1.016 1.016)
			(drill 0.7112)
			(layers "*.Cu" "*.Mask")
			(remove_unused_layers no)
			(net "T7_BLAD3_EN")
			(clearance 0.1016)
			(thermal_gap 0.1016)
		)
		(pad "A68" thru_hole circle
			(at 1.999996 69.000116 270)
			(size 1.016 1.016)
			(drill 0.7112)
			(layers "*.Cu" "*.Mask")
			(remove_unused_layers no)
			(net "TP_T7_BLAD4_EN")
			(clearance 0.1016)
			(thermal_gap 0.1016)
		)
		(pad "A69" thru_hole circle
			(at 0 70.000114 270)
			(size 1.016 1.016)
			(drill 0.7112)
			(layers "*.Cu" "*.Mask")
			(remove_unused_layers no)
			(net "GND")
			(clearance 0.1016)
			(thermal_gap 0.1016)
		)
		(pad "A70" thru_hole circle
			(at 1.999996 71.000112 270)
			(size 1.016 1.016)
			(drill 0.7112)
			(layers "*.Cu" "*.Mask")
			(remove_unused_layers no)
			(net "T7_BLAD1_RXD")
			(clearance 0.1016)
			(thermal_gap 0.1016)
		)
		(pad "A71" thru_hole circle
			(at 0 72.00011 270)
			(size 1.016 1.016)
			(drill 0.7112)
			(layers "*.Cu" "*.Mask")
			(remove_unused_layers no)
			(net "T7_BLAD1_TXD")
			(clearance 0.1016)
			(thermal_gap 0.1016)
		)
		(pad "A72" thru_hole circle
			(at 1.999996 73.000108 270)
			(size 1.016 1.016)
			(drill 0.7112)
			(layers "*.Cu" "*.Mask")
			(remove_unused_layers no)
			(net "T7_BLAD2_RXD")
			(clearance 0.1016)
			(thermal_gap 0.1016)
		)
		(pad "A73" thru_hole circle
			(at 0 74.000106 270)
			(size 1.016 1.016)
			(drill 0.7112)
			(layers "*.Cu" "*.Mask")
			(remove_unused_layers no)
			(net "T7_BLAD2_TXD")
			(clearance 0.1016)
			(thermal_gap 0.1016)
		)
		(pad "A74" thru_hole circle
			(at 1.999996 75.000104 270)
			(size 1.016 1.016)
			(drill 0.7112)
			(layers "*.Cu" "*.Mask")
			(remove_unused_layers no)
			(net "GND")
			(clearance 0.1016)
			(thermal_gap 0.1016)
		)
		(pad "A75" thru_hole circle
			(at 0 76.000102 270)
			(size 1.016 1.016)
			(drill 0.7112)
			(layers "*.Cu" "*.Mask")
			(remove_unused_layers no)
			(net "T7_BLAD3_RXD")
			(clearance 0.1016)
			(thermal_gap 0.1016)
		)
		(pad "A76" thru_hole circle
			(at 1.999996 77.0001 270)
			(size 1.016 1.016)
			(drill 0.7112)
			(layers "*.Cu" "*.Mask")
			(remove_unused_layers no)
			(net "T7_BLAD3_TXD")
			(clearance 0.1016)
			(thermal_gap 0.1016)
		)
	)
)
